# T6G (Grand Teton) — schematic netlist excerpt (pin names and nets, part order shuffled) for the footprints in the layout excerpt that follows; sources: Cadence DE-HDL packaged netlist, KiCad conversion of 04192023_DAF0TMB3IC0_F0TG_MB_C_brd_V02_OCP.brd

R2476  Q_RES  200K 1% EMPTY  pkg 0402LF  page 148 : A = SMB_PCIE_M2_0_EN ; B = PWRGD_P1V8_AUX_R
R42  Q_RES  0 5% CHIP  pkg 0402LF  page 131 : A = USB2_P11_DN ; B = USB2_CPU0_P11_DN

(kicad_pcb
	(version 20260206)
	(generator "pcbnew")
	(generator_version "10.0")
	(general
		(thickness 1.6)
		(legacy_teardrops no)
	)
	(paper "A4")
	(title_block
		(title "04192023_DAF0TMB3IC0_F0TG_MB_C_brd_V02_OCP.brd")
		(comment 1 "Grand Teton / footprints 797-798 of 8354")
	)
	(layers
		(0 "F.Cu" signal "TOP")
		(4 "In1.Cu" signal "GND")
		(6 "In2.Cu" signal "IN1")
		(8 "In3.Cu" signal "GND1")
		(10 "In4.Cu" signal "IN2")
		(12 "In5.Cu" signal "GND2")
		(14 "In6.Cu" signal "IN3")
		(16 "In7.Cu" signal "GND3")
		(18 "In8.Cu" signal "VCC")
		(20 "In9.Cu" signal "VCC1")
		(22 "In10.Cu" signal "GND4")
		(24 "In11.Cu" signal "IN4")
		(26 "In12.Cu" signal "GND5")
		(28 "In13.Cu" signal "IN5")
		(30 "In14.Cu" signal "GND6")
		(32 "In15.Cu" signal "IN6")
		(34 "In16.Cu" signal "GND7")
		(2 "B.Cu" signal "BOTTOM")
		(9 "F.Adhes" user "F.Adhesive")
		(11 "B.Adhes" user "B.Adhesive")
		(13 "F.Paste" user "Package Geometry/Pastemask Top")
		(15 "B.Paste" user "Package Geometry/Pastemask Bottom")
		(5 "F.SilkS" user "Ref Des/Silkscreen Top")
		(7 "B.SilkS" user "Ref Des/Silkscreen Bottom")
		(1 "F.Mask" user "Board Geometry/Soldermask Top")
		(3 "B.Mask" user "Board Geometry/Soldermask Bottom")
		(17 "Dwgs.User" user "User.Drawings")
		(19 "Cmts.User" user "User.Comments")
		(21 "Eco1.User" user "User.Eco1")
		(23 "Eco2.User" user "User.Eco2")
		(25 "Edge.Cuts" user "Board Geometry/Outline")
		(27 "Margin" user)
		(31 "F.CrtYd" user "Package Geometry/Place Bound Top")
		(29 "B.CrtYd" user "Package Geometry/Place Bound Bottom")
		(35 "F.Fab" user "Ref Des/Assembly Top")
		(33 "B.Fab" user "Ref Des/Assembly Bottom")
	)
	(footprint ""
		(layer "F.Cu")
		(at 389.497316 -22.789134 90)
		(property "Reference" "R42"
			(at 0 0 90)
			(layer "F.SilkS")
			(hide yes)
			(effects
				(font
					(size 1.27 1.27)
				)
			)
		)
		(property "Value" ""
			(at 0 0 90)
			(layer "F.Fab")
			(effects
				(font
					(size 1.27 1.27)
				)
			)
		)
		(duplicate_pad_numbers_are_jumpers no)
		(fp_line
			(start 0.7874 -0.4064)
			(end 0.7874 0.011684)
			(stroke
				(width 0.1524)
				(type default)
			)
			(layer "F.SilkS")
		)
		(fp_line
			(start -0.7874 -0.4064)
			(end 0.7874 -0.4064)
			(stroke
				(width 0.1524)
				(type default)
			)
			(layer "F.SilkS")
		)
		(fp_line
			(start -0.7874 0.011684)
			(end -0.7874 -0.4064)
			(stroke
				(width 0.1524)
				(type default)
			)
			(layer "F.SilkS")
		)
		(fp_line
			(start -0.12065 -0.305054)
			(end -0.12065 -0.2794)
			(stroke
				(width 0.1)
				(type default)
			)
			(layer "F.Fab")
		)
		(fp_line
			(start -0.67945 -0.305054)
			(end -0.12065 -0.305054)
			(stroke
				(width 0.1)
				(type default)
			)
			(layer "F.Fab")
		)
		(fp_line
			(start 0.67945 -0.3048)
			(end 0.67945 0.3048)
			(stroke
				(width 0.1)
				(type default)
			)
			(layer "F.Fab")
		)
		(fp_line
			(start 0.12065 -0.3048)
			(end 0.67945 -0.3048)
			(stroke
				(width 0.1)
				(type default)
			)
			(layer "F.Fab")
		)
		(fp_line
			(start 0.12065 -0.2794)
			(end 0.12065 -0.3048)
			(stroke
				(width 0.1)
				(type default)
			)
			(layer "F.Fab")
		)
		(fp_line
			(start -0.12065 -0.2794)
			(end 0.12065 -0.2794)
			(stroke
				(width 0.1)
				(type default)
			)
			(layer "F.Fab")
		)
		(fp_line
			(start 0.120396 0.2794)
			(end -0.12065 0.2794)
			(stroke
				(width 0.1)
				(type default)
			)
			(layer "F.Fab")
		)
		(fp_line
			(start -0.12065 0.2794)
			(end -0.12065 0.3048)
			(stroke
				(width 0.1)
				(type default)
			)
			(layer "F.Fab")
		)
		(fp_line
			(start 0.67945 0.3048)
			(end 0.120396 0.3048)
			(stroke
				(width 0.1)
				(type default)
			)
			(layer "F.Fab")
		)
		(fp_line
			(start 0.120396 0.3048)
			(end 0.120396 0.2794)
			(stroke
				(width 0.1)
				(type default)
			)
			(layer "F.Fab")
		)
		(fp_line
			(start -0.12065 0.3048)
			(end -0.67945 0.3048)
			(stroke
				(width 0.1)
				(type default)
			)
			(layer "F.Fab")
		)
		(fp_line
			(start -0.67945 0.3048)
			(end -0.67945 -0.305054)
			(stroke
				(width 0.1)
				(type default)
			)
			(layer "F.Fab")
		)
		(pad "1" smd circle
			(at -0.40005 0 90)
			(size 0 0)
			(layers "F.Cu" "F.Mask" "F.Paste")
			(net "USB2_P11_DN")
		)
		(pad "2" smd circle
			(at 0.40005 0 90)
			(size 0 0)
			(layers "F.Cu" "F.Mask" "F.Paste")
			(net "USB2_CPU0_P11_DN")
		)
	)
	(footprint ""
		(layer "F.Cu")
		(at 158.82874 -44.985686 90)
		(property "Reference" "R2476"
			(at 0 0 90)
			(layer "F.SilkS")
			(hide yes)
			(effects
				(font
					(size 1.27 1.27)
				)
			)
		)
		(property "Value" ""
			(at 0 0 90)
			(layer "F.Fab")
			(effects
				(font
					(size 1.27 1.27)
				)
			)
		)
		(duplicate_pad_numbers_are_jumpers no)
		(fp_line
			(start 0.7874 -0.4064)
			(end 0.7874 0.4064)
			(stroke
				(width 0.1524)
				(type default)
			)
			(layer "F.SilkS")
		)
		(fp_line
			(start -0.7874 -0.4064)
			(end 0.7874 -0.4064)
			(stroke
				(width 0.1524)
				(type default)
			)
			(layer "F.SilkS")
		)
		(fp_line
			(start 0.7874 0.4064)
			(end -0.7874 0.4064)
			(stroke
				(width 0.1524)
				(type default)
			)
			(layer "F.SilkS")
		)
		(fp_line
			(start -0.7874 0.4064)
			(end -0.7874 -0.4064)
			(stroke
				(width 0.1524)
				(type default)
			)
			(layer "F.SilkS")
		)
		(fp_line
			(start -0.12065 -0.305054)
			(end -0.12065 -0.2794)
			(stroke
				(width 0.1)
				(type default)
			)
			(layer "F.Fab")
		)
		(fp_line
			(start -0.67945 -0.305054)
			(end -0.12065 -0.305054)
			(stroke
				(width 0.1)
				(type default)
			)
			(layer "F.Fab")
		)
		(fp_line
			(start 0.67945 -0.3048)
			(end 0.67945 0.3048)
			(stroke
				(width 0.1)
				(type default)
			)
			(layer "F.Fab")
		)
		(fp_line
			(start 0.12065 -0.3048)
			(end 0.67945 -0.3048)
			(stroke
				(width 0.1)
				(type default)
			)
			(layer "F.Fab")
		)
		(fp_line
			(start 0.12065 -0.2794)
			(end 0.12065 -0.3048)
			(stroke
				(width 0.1)
				(type default)
			)
			(layer "F.Fab")
		)
		(fp_line
			(start -0.12065 -0.2794)
			(end 0.12065 -0.2794)
			(stroke
				(width 0.1)
				(type default)
			)
			(layer "F.Fab")
		)
		(fp_line
			(start 0.120396 0.2794)
			(end -0.12065 0.2794)
			(stroke
				(width 0.1)
				(type default)
			)
			(layer "F.Fab")
		)
		(fp_line
			(start -0.12065 0.2794)
			(end -0.12065 0.3048)
			(stroke
				(width 0.1)
				(type default)
			)
			(layer "F.Fab")
		)
		(fp_line
			(start 0.67945 0.3048)
			(end 0.120396 0.3048)
			(stroke
				(width 0.1)
				(type default)
			)
			(layer "F.Fab")
		)
		(fp_line
			(start 0.120396 0.3048)
			(end 0.120396 0.2794)
			(stroke
				(width 0.1)
				(type default)
			)
			(layer "F.Fab")
		)
		(fp_line
			(start -0.12065 0.3048)
			(end -0.67945 0.3048)
			(stroke
				(width 0.1)
				(type default)
			)
			(layer "F.Fab")
		)
		(fp_line
			(start -0.67945 0.3048)
			(end -0.67945 -0.305054)
			(stroke
				(width 0.1)
				(type default)
			)
			(layer "F.Fab")
		)
		(pad "1" smd circle
			(at -0.40005 0 90)
			(size 0 0)
			(layers "F.Cu" "F.Mask" "F.Paste")
			(net "SMB_PCIE_M2_0_EN")
		)
		(pad "2" smd circle
			(at 0.40005 0 90)
			(size 0 0)
			(layers "F.Cu" "F.Mask" "F.Paste")
			(net "PWRGD_P1V8_AUX_R")
		)
	)
)
